(kicad_pcb
	(version 20260206)
	(generator "pcbnew")
	(generator_version "10.0")
	(general
		(thickness 1.6)
		(legacy_teardrops no)
	)
	(paper "A4")
	(title_block
		(title "panther-plus-userver — 13130-1b_20150205.brd")
		(comment 1 "Honey Badger (Wiwynn) / footprint 1214 of 1509 (DIMM3), pads 1-8 of 210")
	)
	(layers
		(0 "F.Cu" signal "TOP")
		(4 "In1.Cu" signal "L2")
		(6 "In2.Cu" signal "L3")
		(8 "In3.Cu" signal "L4")
		(10 "In4.Cu" signal "L5")
		(12 "In5.Cu" signal "L6")
		(14 "In6.Cu" signal "L7")
		(16 "In7.Cu" signal "L8")
		(18 "In8.Cu" signal "L9")
		(20 "In9.Cu" signal "L10")
		(22 "In10.Cu" signal "L11")
		(2 "B.Cu" signal "BOTTOM")
		(9 "F.Adhes" user "F.Adhesive")
		(11 "B.Adhes" user "B.Adhesive")
		(13 "F.Paste" user "Package Geometry/Pastemask Top")
		(15 "B.Paste" user "Package Geometry/Pastemask Bottom")
		(5 "F.SilkS" user "Ref Des/Silkscreen Top")
		(7 "B.SilkS" user "Ref Des/Silkscreen Bottom")
		(1 "F.Mask" user "Board Geometry/Soldermask Top")
		(3 "B.Mask" user "Board Geometry/Soldermask Bottom")
		(17 "Dwgs.User" user "User.Drawings")
		(19 "Cmts.User" user "User.Comments")
		(21 "Eco1.User" user "User.Eco1")
		(23 "Eco2.User" user "User.Eco2")
		(25 "Edge.Cuts" user "Board Geometry/Outline")
		(27 "Margin" user)
		(31 "F.CrtYd" user "Package Geometry/Place Bound Top")
		(29 "B.CrtYd" user "Package Geometry/Place Bound Bottom")
		(35 "F.Fab" user "Ref Des/Assembly Top")
		(33 "B.Fab" user "Ref Des/Assembly Bottom")
	)
	(footprint ""
		(layer "B.Cu")
		(at 159.999934 -5.790692)
		(property "Reference" "DIMM3"
			(at 0 0 0)
			(layer "B.SilkS")
			(hide yes)
			(effects
				(font
					(size 1.27 1.27)
				)
				(justify mirror)
			)
		)
		(property "Value" "DDR3-204P-142-COLAY-1-GP-U"
			(at 41.312338 -16.676878 0)
			(unlocked yes)
			(layer "B.Fab")
			(hide yes)
			(effects
				(font
					(size 1.016 1.016)
					(thickness 0.1524)
				)
				(justify mirror)
			)
		)
		(property "Device Type" "AS0A626-J8R6-7H-COLAY-1"
			(at 41.312338 -18.200878 0)
			(unlocked yes)
			(layer "B.Fab")
			(hide yes)
			(effects
				(font
					(size 1.016 1.016)
					(thickness 0.1524)
				)
				(justify mirror)
			)
		)
		(duplicate_pad_numbers_are_jumpers no)
		(pad "" np_thru_hole circle
			(at -33.399984 0 180)
			(size 0.254 0.254)
			(drill 1.6002)
			(layers "*.Cu" "*.Mask")
			(clearance 1.0287)
			(thermal_gap 1.0287)
		)
		(pad "" np_thru_hole circle
			(at 33.399984 0 180)
			(size 0.254 0.254)
			(drill 1.1176)
			(layers "*.Cu" "*.Mask")
			(clearance 0.7874)
			(thermal_gap 0.7874)
		)
		(pad "1" smd custom
			(at -31.649924 -4.100068 180)
			(size 0.1143 0.1143)
			(layers "B.Cu" "B.Mask" "B.Paste")
			(net "DDR3_M_B_VREF_DQ0")
			(options
				(clearance outline)
				(anchor circle)
			)
			(primitives
				(gr_poly
					(pts
						(xy 0 -0.9017) (xy -0.03175 -0.89916) (xy -0.0635 -0.889) (xy -0.09144 -0.87376) (xy -0.11684 -0.85344)
						(xy -0.13716 -0.82804) (xy -0.1524 -0.8001) (xy -0.16256 -0.76835) (xy -0.1651 -0.7366) (xy -0.1651 -0.44958)
						(xy -0.17272 -0.44196) (xy -0.19812 -0.4064) (xy -0.2032 -0.39624) (xy -0.20701 -0.38735) (xy -0.21209 -0.37719)
						(xy -0.2159 -0.36703) (xy -0.21844 -0.35687) (xy -0.22225 -0.34544) (xy -0.22352 -0.33528) (xy -0.22606 -0.32512)
						(xy -0.22733 -0.31369) (xy -0.22733 -0.30353) (xy -0.2286 -0.2921) (xy -0.22733 -0.28067) (xy -0.22733 -0.27051)
						(xy -0.22606 -0.25908) (xy -0.22352 -0.24892) (xy -0.22225 -0.23876) (xy -0.21844 -0.22733) (xy -0.2159 -0.21717)
						(xy -0.21209 -0.20701) (xy -0.20701 -0.19685) (xy -0.2032 -0.18796) (xy -0.19812 -0.1778) (xy -0.17272 -0.14224)
						(xy -0.1651 -0.13462) (xy -0.1651 0.7366) (xy -0.16256 0.76835) (xy -0.1524 0.8001) (xy -0.13716 0.82804)
						(xy -0.11684 0.85344) (xy -0.09144 0.87376) (xy -0.0635 0.889) (xy -0.03175 0.89916) (xy 0 0.9017)
						(xy 0.03175 0.89916) (xy 0.0635 0.889) (xy 0.09144 0.87376) (xy 0.11684 0.85344) (xy 0.13716 0.82804)
						(xy 0.1524 0.8001) (xy 0.16256 0.76835) (xy 0.1651 0.7366) (xy 0.1651 -0.13462) (xy 0.17272 -0.14224)
						(xy 0.19812 -0.1778) (xy 0.2032 -0.18796) (xy 0.20701 -0.19685) (xy 0.21209 -0.20701) (xy 0.2159 -0.21717)
						(xy 0.21844 -0.22733) (xy 0.22225 -0.23876) (xy 0.22352 -0.24892) (xy 0.22606 -0.25908) (xy 0.22733 -0.27051)
						(xy 0.22733 -0.28067) (xy 0.2286 -0.2921) (xy 0.22733 -0.30353) (xy 0.22733 -0.31369) (xy 0.22606 -0.32512)
						(xy 0.22352 -0.33528) (xy 0.22225 -0.34544) (xy 0.21844 -0.35687) (xy 0.2159 -0.36703) (xy 0.21209 -0.37719)
						(xy 0.20701 -0.38735) (xy 0.2032 -0.39624) (xy 0.19812 -0.4064) (xy 0.17272 -0.44196) (xy 0.1651 -0.44958)
						(xy 0.1651 -0.7366) (xy 0.16256 -0.76835) (xy 0.1524 -0.8001) (xy 0.13716 -0.82804) (xy 0.11684 -0.85344)
						(xy 0.09144 -0.87376) (xy 0.0635 -0.889) (xy 0.03175 -0.89916)
					)
					(width 0)
					(fill yes)
				)
			)
		)
		(pad "2" smd custom
			(at -31.34995 4.100068 180)
			(size 0.1143 0.1143)
			(layers "B.Cu" "B.Mask" "B.Paste")
			(net "GND")
			(options
				(clearance outline)
				(anchor circle)
			)
			(primitives
				(gr_poly
					(pts
						(xy 0 -0.9017) (xy -0.03175 -0.89916) (xy -0.0635 -0.889) (xy -0.09144 -0.87376) (xy -0.11684 -0.85344)
						(xy -0.13716 -0.82804) (xy -0.1524 -0.8001) (xy -0.16256 -0.76835) (xy -0.1651 -0.7366) (xy -0.1651 0.13462)
						(xy -0.17272 0.14224) (xy -0.19812 0.1778) (xy -0.2032 0.18796) (xy -0.20701 0.19685) (xy -0.21209 0.20701)
						(xy -0.2159 0.21717) (xy -0.21844 0.22733) (xy -0.22225 0.23876) (xy -0.22352 0.24892) (xy -0.22606 0.25908)
						(xy -0.22733 0.27051) (xy -0.22733 0.28067) (xy -0.2286 0.2921) (xy -0.22733 0.30353) (xy -0.22733 0.31369)
						(xy -0.22606 0.32512) (xy -0.22352 0.33528) (xy -0.22225 0.34544) (xy -0.21844 0.35687) (xy -0.2159 0.36703)
						(xy -0.21209 0.37719) (xy -0.20701 0.38735) (xy -0.2032 0.39624) (xy -0.19812 0.4064) (xy -0.17272 0.44196)
						(xy -0.1651 0.44958) (xy -0.1651 0.7366) (xy -0.16256 0.76835) (xy -0.1524 0.8001) (xy -0.13716 0.82804)
						(xy -0.11684 0.85344) (xy -0.09144 0.87376) (xy -0.0635 0.889) (xy -0.03175 0.89916) (xy 0 0.9017)
						(xy 0.03175 0.89916) (xy 0.0635 0.889) (xy 0.09144 0.87376) (xy 0.11684 0.85344) (xy 0.13716 0.82804)
						(xy 0.1524 0.8001) (xy 0.16256 0.76835) (xy 0.1651 0.7366) (xy 0.1651 0.44958) (xy 0.17272 0.44196)
						(xy 0.19812 0.4064) (xy 0.2032 0.39624) (xy 0.20701 0.38735) (xy 0.21209 0.37719) (xy 0.2159 0.36703)
						(xy 0.21844 0.35687) (xy 0.22225 0.34544) (xy 0.22352 0.33528) (xy 0.22606 0.32512) (xy 0.22733 0.31369)
						(xy 0.22733 0.30353) (xy 0.2286 0.2921) (xy 0.22733 0.28067) (xy 0.22733 0.27051) (xy 0.22606 0.25908)
						(xy 0.22352 0.24892) (xy 0.22225 0.23876) (xy 0.21844 0.22733) (xy 0.2159 0.21717) (xy 0.21209 0.20701)
						(xy 0.20701 0.19685) (xy 0.2032 0.18796) (xy 0.19812 0.1778) (xy 0.17272 0.14224) (xy 0.1651 0.13462)
						(xy 0.1651 -0.7366) (xy 0.16256 -0.76835) (xy 0.1524 -0.8001) (xy 0.13716 -0.82804) (xy 0.11684 -0.85344)
						(xy 0.09144 -0.87376) (xy 0.0635 -0.889) (xy 0.03175 -0.89916)
					)
					(width 0)
					(fill yes)
				)
			)
		)
		(pad "3" smd custom
			(at -31.049976 -4.100068 180)
			(size 0.1143 0.1143)
			(layers "B.Cu" "B.Mask" "B.Paste")
			(net "GND")
			(options
				(clearance outline)
				(anchor circle)
			)
			(primitives
				(gr_poly
					(pts
						(xy 0 -0.9017) (xy -0.03175 -0.89916) (xy -0.0635 -0.889) (xy -0.09144 -0.87376) (xy -0.11684 -0.85344)
						(xy -0.13716 -0.82804) (xy -0.1524 -0.8001) (xy -0.16256 -0.76835) (xy -0.1651 -0.7366) (xy -0.1651 -0.19685)
						(xy -0.17272 -0.18923) (xy -0.17907 -0.18034) (xy -0.18669 -0.17145) (xy -0.19177 -0.16256) (xy -0.19812 -0.15367)
						(xy -0.20828 -0.13335) (xy -0.21971 -0.10287) (xy -0.22225 -0.09271) (xy -0.22479 -0.08128) (xy -0.22606 -0.07112)
						(xy -0.2286 -0.05969) (xy -0.2286 -0.01651) (xy -0.22606 -0.00508) (xy -0.22479 0.00508) (xy -0.22225 0.01651)
						(xy -0.21971 0.02667) (xy -0.20828 0.05715) (xy -0.19812 0.07747) (xy -0.19177 0.08636) (xy -0.18669 0.09525)
						(xy -0.17907 0.10414) (xy -0.17272 0.11303) (xy -0.1651 0.12065) (xy -0.1651 0.7366) (xy -0.16256 0.76835)
						(xy -0.1524 0.8001) (xy -0.13716 0.82804) (xy -0.11684 0.85344) (xy -0.09144 0.87376) (xy -0.0635 0.889)
						(xy -0.03175 0.89916) (xy 0 0.9017) (xy 0.03175 0.89916) (xy 0.0635 0.889) (xy 0.09144 0.87376)
						(xy 0.11684 0.85344) (xy 0.13716 0.82804) (xy 0.1524 0.8001) (xy 0.16256 0.76835) (xy 0.1651 0.7366)
						(xy 0.1651 0.11938) (xy 0.17272 0.11176) (xy 0.19812 0.0762) (xy 0.2032 0.06604) (xy 0.20701 0.05715)
						(xy 0.21209 0.04699) (xy 0.2159 0.03683) (xy 0.21844 0.02667) (xy 0.22225 0.01524) (xy 0.22352 0.00508)
						(xy 0.22606 -0.00508) (xy 0.22733 -0.01651) (xy 0.22733 -0.02667) (xy 0.2286 -0.0381) (xy 0.22733 -0.04953)
						(xy 0.22733 -0.05969) (xy 0.22606 -0.07112) (xy 0.22352 -0.08128) (xy 0.22225 -0.09144) (xy 0.21844 -0.10287)
						(xy 0.2159 -0.11303) (xy 0.21209 -0.12319) (xy 0.20701 -0.13335) (xy 0.2032 -0.14224) (xy 0.19812 -0.1524)
						(xy 0.17272 -0.18796) (xy 0.1651 -0.19558) (xy 0.1651 -0.7366) (xy 0.16256 -0.76835) (xy 0.1524 -0.8001)
						(xy 0.13716 -0.82804) (xy 0.11684 -0.85344) (xy 0.09144 -0.87376) (xy 0.0635 -0.889) (xy 0.03175 -0.89916)
					)
					(width 0)
					(fill yes)
				)
			)
		)
		(pad "4" smd custom
			(at -30.750002 4.100068 180)
			(size 0.1143 0.1143)
			(layers "B.Cu" "B.Mask" "B.Paste")
			(net "M_B_DQ4")
			(options
				(clearance outline)
				(anchor circle)
			)
			(primitives
				(gr_poly
					(pts
						(xy 0 -0.9017) (xy -0.03175 -0.89916) (xy -0.0635 -0.889) (xy -0.09144 -0.87376) (xy -0.11684 -0.85344)
						(xy -0.13716 -0.82804) (xy -0.1524 -0.8001) (xy -0.16256 -0.76835) (xy -0.1651 -0.7366) (xy -0.1651 -0.11938)
						(xy -0.17272 -0.11176) (xy -0.19812 -0.0762) (xy -0.2032 -0.06604) (xy -0.20701 -0.05715) (xy -0.21209 -0.04699)
						(xy -0.2159 -0.03683) (xy -0.21844 -0.02667) (xy -0.22225 -0.01524) (xy -0.22352 -0.00508) (xy -0.22606 0.00508)
						(xy -0.22733 0.01651) (xy -0.22733 0.02667) (xy -0.2286 0.0381) (xy -0.22733 0.04953) (xy -0.22733 0.05969)
						(xy -0.22606 0.07112) (xy -0.22352 0.08128) (xy -0.22225 0.09144) (xy -0.21844 0.10287) (xy -0.2159 0.11303)
						(xy -0.21209 0.12319) (xy -0.20701 0.13335) (xy -0.2032 0.14224) (xy -0.19812 0.1524) (xy -0.17272 0.18796)
						(xy -0.1651 0.19558) (xy -0.1651 0.7366) (xy -0.16256 0.76835) (xy -0.1524 0.8001) (xy -0.13716 0.82804)
						(xy -0.11684 0.85344) (xy -0.09144 0.87376) (xy -0.0635 0.889) (xy -0.03175 0.89916) (xy 0 0.9017)
						(xy 0.03175 0.89916) (xy 0.0635 0.889) (xy 0.09144 0.87376) (xy 0.11684 0.85344) (xy 0.13716 0.82804)
						(xy 0.1524 0.8001) (xy 0.16256 0.76835) (xy 0.1651 0.7366) (xy 0.1651 0.19685) (xy 0.17272 0.18923)
						(xy 0.17907 0.18034) (xy 0.18669 0.17145) (xy 0.19177 0.16256) (xy 0.19812 0.15367) (xy 0.20828 0.13335)
						(xy 0.21971 0.10287) (xy 0.22225 0.09271) (xy 0.22479 0.08128) (xy 0.22606 0.07112) (xy 0.2286 0.05969)
						(xy 0.2286 0.01651) (xy 0.22606 0.00508) (xy 0.22479 -0.00508) (xy 0.22225 -0.01651) (xy 0.21971 -0.02667)
						(xy 0.20828 -0.05715) (xy 0.19812 -0.07747) (xy 0.19177 -0.08636) (xy 0.18669 -0.09525) (xy 0.17907 -0.10414)
						(xy 0.17272 -0.11303) (xy 0.1651 -0.12065) (xy 0.1651 -0.7366) (xy 0.16256 -0.76835) (xy 0.1524 -0.8001)
						(xy 0.13716 -0.82804) (xy 0.11684 -0.85344) (xy 0.09144 -0.87376) (xy 0.0635 -0.889) (xy 0.03175 -0.89916)
					)
					(width 0)
					(fill yes)
				)
			)
		)
		(pad "5" smd custom
			(at -30.450028 -4.100068 180)
			(size 0.1143 0.1143)
			(layers "B.Cu" "B.Mask" "B.Paste")
			(net "M_B_DQ0")
			(options
				(clearance outline)
				(anchor circle)
			)
			(primitives
				(gr_poly
					(pts
						(xy 0 -0.9017) (xy -0.03175 -0.89916) (xy -0.0635 -0.889) (xy -0.09144 -0.87376) (xy -0.11684 -0.85344)
						(xy -0.13716 -0.82804) (xy -0.1524 -0.8001) (xy -0.16256 -0.76835) (xy -0.1651 -0.7366) (xy -0.1651 -0.44958)
						(xy -0.17272 -0.44196) (xy -0.19812 -0.4064) (xy -0.2032 -0.39624) (xy -0.20701 -0.38735) (xy -0.21209 -0.37719)
						(xy -0.2159 -0.36703) (xy -0.21844 -0.35687) (xy -0.22225 -0.34544) (xy -0.22352 -0.33528) (xy -0.22606 -0.32512)
						(xy -0.22733 -0.31369) (xy -0.22733 -0.30353) (xy -0.2286 -0.2921) (xy -0.22733 -0.28067) (xy -0.22733 -0.27051)
						(xy -0.22606 -0.25908) (xy -0.22352 -0.24892) (xy -0.22225 -0.23876) (xy -0.21844 -0.22733) (xy -0.2159 -0.21717)
						(xy -0.21209 -0.20701) (xy -0.20701 -0.19685) (xy -0.2032 -0.18796) (xy -0.19812 -0.1778) (xy -0.17272 -0.14224)
						(xy -0.1651 -0.13462) (xy -0.1651 0.7366) (xy -0.16256 0.76835) (xy -0.1524 0.8001) (xy -0.13716 0.82804)
						(xy -0.11684 0.85344) (xy -0.09144 0.87376) (xy -0.0635 0.889) (xy -0.03175 0.89916) (xy 0 0.9017)
						(xy 0.03175 0.89916) (xy 0.0635 0.889) (xy 0.09144 0.87376) (xy 0.11684 0.85344) (xy 0.13716 0.82804)
						(xy 0.1524 0.8001) (xy 0.16256 0.76835) (xy 0.1651 0.7366) (xy 0.1651 -0.13462) (xy 0.17272 -0.14224)
						(xy 0.19812 -0.1778) (xy 0.2032 -0.18796) (xy 0.20701 -0.19685) (xy 0.21209 -0.20701) (xy 0.2159 -0.21717)
						(xy 0.21844 -0.22733) (xy 0.22225 -0.23876) (xy 0.22352 -0.24892) (xy 0.22606 -0.25908) (xy 0.22733 -0.27051)
						(xy 0.22733 -0.28067) (xy 0.2286 -0.2921) (xy 0.22733 -0.30353) (xy 0.22733 -0.31369) (xy 0.22606 -0.32512)
						(xy 0.22352 -0.33528) (xy 0.22225 -0.34544) (xy 0.21844 -0.35687) (xy 0.2159 -0.36703) (xy 0.21209 -0.37719)
						(xy 0.20701 -0.38735) (xy 0.2032 -0.39624) (xy 0.19812 -0.4064) (xy 0.17272 -0.44196) (xy 0.1651 -0.44958)
						(xy 0.1651 -0.7366) (xy 0.16256 -0.76835) (xy 0.1524 -0.8001) (xy 0.13716 -0.82804) (xy 0.11684 -0.85344)
						(xy 0.09144 -0.87376) (xy 0.0635 -0.889) (xy 0.03175 -0.89916)
					)
					(width 0)
					(fill yes)
				)
			)
		)
		(pad "6" smd custom
			(at -30.150054 4.100068 180)
			(size 0.1143 0.1143)
			(layers "B.Cu" "B.Mask" "B.Paste")
			(net "M_B_DQ5")
			(options
				(clearance outline)
				(anchor circle)
			)
			(primitives
				(gr_poly
					(pts
						(xy 0 -0.9017) (xy -0.03175 -0.89916) (xy -0.0635 -0.889) (xy -0.09144 -0.87376) (xy -0.11684 -0.85344)
						(xy -0.13716 -0.82804) (xy -0.1524 -0.8001) (xy -0.16256 -0.76835) (xy -0.1651 -0.7366) (xy -0.1651 0.13462)
						(xy -0.17272 0.14224) (xy -0.19812 0.1778) (xy -0.2032 0.18796) (xy -0.20701 0.19685) (xy -0.21209 0.20701)
						(xy -0.2159 0.21717) (xy -0.21844 0.22733) (xy -0.22225 0.23876) (xy -0.22352 0.24892) (xy -0.22606 0.25908)
						(xy -0.22733 0.27051) (xy -0.22733 0.28067) (xy -0.2286 0.2921) (xy -0.22733 0.30353) (xy -0.22733 0.31369)
						(xy -0.22606 0.32512) (xy -0.22352 0.33528) (xy -0.22225 0.34544) (xy -0.21844 0.35687) (xy -0.2159 0.36703)
						(xy -0.21209 0.37719) (xy -0.20701 0.38735) (xy -0.2032 0.39624) (xy -0.19812 0.4064) (xy -0.17272 0.44196)
						(xy -0.1651 0.44958) (xy -0.1651 0.7366) (xy -0.16256 0.76835) (xy -0.1524 0.8001) (xy -0.13716 0.82804)
						(xy -0.11684 0.85344) (xy -0.09144 0.87376) (xy -0.0635 0.889) (xy -0.03175 0.89916) (xy 0 0.9017)
						(xy 0.03175 0.89916) (xy 0.0635 0.889) (xy 0.09144 0.87376) (xy 0.11684 0.85344) (xy 0.13716 0.82804)
						(xy 0.1524 0.8001) (xy 0.16256 0.76835) (xy 0.1651 0.7366) (xy 0.1651 0.44958) (xy 0.17272 0.44196)
						(xy 0.19812 0.4064) (xy 0.2032 0.39624) (xy 0.20701 0.38735) (xy 0.21209 0.37719) (xy 0.2159 0.36703)
						(xy 0.21844 0.35687) (xy 0.22225 0.34544) (xy 0.22352 0.33528) (xy 0.22606 0.32512) (xy 0.22733 0.31369)
						(xy 0.22733 0.30353) (xy 0.2286 0.2921) (xy 0.22733 0.28067) (xy 0.22733 0.27051) (xy 0.22606 0.25908)
						(xy 0.22352 0.24892) (xy 0.22225 0.23876) (xy 0.21844 0.22733) (xy 0.2159 0.21717) (xy 0.21209 0.20701)
						(xy 0.20701 0.19685) (xy 0.2032 0.18796) (xy 0.19812 0.1778) (xy 0.17272 0.14224) (xy 0.1651 0.13462)
						(xy 0.1651 -0.7366) (xy 0.16256 -0.76835) (xy 0.1524 -0.8001) (xy 0.13716 -0.82804) (xy 0.11684 -0.85344)
						(xy 0.09144 -0.87376) (xy 0.0635 -0.889) (xy 0.03175 -0.89916)
					)
					(width 0)
					(fill yes)
				)
			)
		)
	)
)
